(kicad_pcb
	(version 20260206)
	(generator "pcbnew")
	(generator_version "10.0")
	(general
		(thickness 1.6)
		(legacy_teardrops no)
	)
	(paper "A4")
	(title_block
		(title "v2-pdb — ms_pdb_v2.brd")
		(comment 1 "Open CloudServer (Microsoft) / footprints 342-346 of 348")
	)
	(layers
		(0 "F.Cu" signal "TOP")
		(4 "In1.Cu" signal "GND")
		(6 "In2.Cu" signal "IN1")
		(8 "In3.Cu" signal "VCC")
		(10 "In4.Cu" signal "VCC1")
		(12 "In5.Cu" signal "IN2")
		(14 "In6.Cu" signal "GND1")
		(2 "B.Cu" signal "BOTTOM")
		(9 "F.Adhes" user "F.Adhesive")
		(11 "B.Adhes" user "B.Adhesive")
		(13 "F.Paste" user "Package Geometry/Pastemask Top")
		(15 "B.Paste" user "Package Geometry/Pastemask Bottom")
		(5 "F.SilkS" user "Ref Des/Silkscreen Top")
		(7 "B.SilkS" user "Ref Des/Silkscreen Bottom")
		(1 "F.Mask" user "Board Geometry/Soldermask Top")
		(3 "B.Mask" user "Board Geometry/Soldermask Bottom")
		(17 "Dwgs.User" user "User.Drawings")
		(19 "Cmts.User" user "User.Comments")
		(21 "Eco1.User" user "User.Eco1")
		(23 "Eco2.User" user "User.Eco2")
		(25 "Edge.Cuts" user "Board Geometry/Outline")
		(27 "Margin" user)
		(31 "F.CrtYd" user "Package Geometry/Place Bound Top")
		(29 "B.CrtYd" user "Package Geometry/Place Bound Bottom")
		(35 "F.Fab" user "Ref Des/Assembly Top")
		(33 "B.Fab" user "Ref Des/Assembly Bottom")
	)
	(footprint ""
		(layer "B.Cu")
		(at 97.827084 -84.356956 90)
		(property "Reference" "C93"
			(at -1.839214 2.474468 270)
			(unlocked yes)
			(layer "B.SilkS")
			(effects
				(font
					(size 0.7874 0.5842)
					(thickness 0.1524)
				)
				(justify left mirror)
			)
		)
		(property "Value" ""
			(at 0 0 90)
			(layer "B.Fab")
			(effects
				(font
					(size 1.27 1.27)
				)
				(justify mirror)
			)
		)
		(duplicate_pad_numbers_are_jumpers no)
		(fp_line
			(start 0.7874 -0.4064)
			(end -0.7874 -0.4064)
			(stroke
				(width 0.1524)
				(type default)
			)
			(layer "B.SilkS")
		)
		(fp_line
			(start -0.7874 -0.4064)
			(end -0.7874 0.4064)
			(stroke
				(width 0.1524)
				(type default)
			)
			(layer "B.SilkS")
		)
		(fp_line
			(start 0 0.381)
			(end 0 -0.381)
			(stroke
				(width 0.1524)
				(type default)
			)
			(layer "B.SilkS")
		)
		(fp_line
			(start 0.7874 0.4064)
			(end 0.7874 -0.4064)
			(stroke
				(width 0.1524)
				(type default)
			)
			(layer "B.SilkS")
		)
		(fp_line
			(start -0.7874 0.4064)
			(end 0.7874 0.4064)
			(stroke
				(width 0.1524)
				(type default)
			)
			(layer "B.SilkS")
		)
		(fp_poly
			(pts
				(xy 0.5334 0.254) (xy 0.635 0.254) (xy 0.635 0.2286) (xy 0.635 -0.254) (xy 0.5334 -0.254) (xy 0.5334 -0.2794)
				(xy -0.5334 -0.2794) (xy -0.5334 -0.254) (xy -0.635 -0.254) (xy -0.635 0.254) (xy -0.5334 0.254)
				(xy -0.5334 0.2794) (xy 0.508 0.2794) (xy 0.5334 0.2794)
			)
			(stroke
				(width 0)
				(type default)
			)
			(fill no)
			(layer "B.CrtYd")
		)
		(pad "1" smd rect
			(at -0.40005 0 270)
			(size 0.4572 0.508)
			(layers "B.Cu" "B.Mask" "B.Paste")
			(net "P3V3_BUF")
		)
		(pad "2" smd rect
			(at 0.40005 0 270)
			(size 0.4572 0.508)
			(layers "B.Cu" "B.Mask" "B.Paste")
			(net "GND")
		)
	)
	(footprint ""
		(layer "B.Cu")
		(at 96.609408 -483.043992)
		(property "Reference" "C96"
			(at 2.285238 1.540764 0)
			(unlocked yes)
			(layer "B.SilkS")
			(effects
				(font
					(size 0.7874 0.5842)
					(thickness 0.1524)
				)
				(justify left mirror)
			)
		)
		(property "Value" ""
			(at 0 0 0)
			(layer "B.Fab")
			(effects
				(font
					(size 1.27 1.27)
				)
				(justify mirror)
			)
		)
		(duplicate_pad_numbers_are_jumpers no)
		(fp_line
			(start -0.7874 -0.4064)
			(end -0.7874 0.4064)
			(stroke
				(width 0.1524)
				(type default)
			)
			(layer "B.SilkS")
		)
		(fp_line
			(start -0.7874 0.4064)
			(end 0.7874 0.4064)
			(stroke
				(width 0.1524)
				(type default)
			)
			(layer "B.SilkS")
		)
		(fp_line
			(start 0 0.381)
			(end 0 -0.381)
			(stroke
				(width 0.1524)
				(type default)
			)
			(layer "B.SilkS")
		)
		(fp_line
			(start 0.7874 -0.4064)
			(end -0.7874 -0.4064)
			(stroke
				(width 0.1524)
				(type default)
			)
			(layer "B.SilkS")
		)
		(fp_line
			(start 0.7874 0.4064)
			(end 0.7874 -0.4064)
			(stroke
				(width 0.1524)
				(type default)
			)
			(layer "B.SilkS")
		)
		(fp_poly
			(pts
				(xy 0.5334 0.254) (xy 0.635 0.254) (xy 0.635 0.2286) (xy 0.635 -0.254) (xy 0.5334 -0.254) (xy 0.5334 -0.2794)
				(xy -0.5334 -0.2794) (xy -0.5334 -0.254) (xy -0.635 -0.254) (xy -0.635 0.254) (xy -0.5334 0.254)
				(xy -0.5334 0.2794) (xy 0.508 0.2794) (xy 0.5334 0.2794)
			)
			(stroke
				(width 0)
				(type default)
			)
			(fill no)
			(layer "B.CrtYd")
		)
		(pad "1" smd rect
			(at -0.40005 0 180)
			(size 0.4572 0.508)
			(layers "B.Cu" "B.Mask" "B.Paste")
			(net "P3V3_BUF")
		)
		(pad "2" smd rect
			(at 0.40005 0 180)
			(size 0.4572 0.508)
			(layers "B.Cu" "B.Mask" "B.Paste")
			(net "GND")
		)
	)
	(footprint ""
		(layer "B.Cu")
		(at 14.010132 -224.098358)
		(property "Reference" ""
			(at 0 0 0)
			(layer "B.SilkS")
			(hide yes)
			(effects
				(font
					(size 1.27 1.27)
				)
				(justify mirror)
			)
		)
		(property "Value" ""
			(at 0 0 0)
			(layer "B.Fab")
			(effects
				(font
					(size 1.27 1.27)
				)
				(justify mirror)
			)
		)
		(duplicate_pad_numbers_are_jumpers no)
		(fp_poly
			(pts
				(arc
					(start 1.4986 0)
					(mid -1.4986 0)
					(end 1.4986 0)
				)
			)
			(stroke
				(width 0)
				(type default)
			)
			(fill no)
			(layer "B.CrtYd")
		)
		(pad "1" smd circle
			(at 0 0 180)
			(size 0.9906 0.9906)
			(layers "B.Cu" "B.Mask" "B.Paste")
			(net "Net_72")
		)
		(zone
			(layer "B.Cu")
			(hatch none 0.5)
			(connect_pads
				(clearance 0)
			)
			(min_thickness 0.25)
			(keepout
				(tracks not_allowed)
				(vias allowed)
				(pads allowed)
				(copperpour not_allowed)
				(footprints allowed)
			)
			(placement
				(enabled no)
				(sheetname "")
			)
			(fill
				(thermal_gap 0.5)
				(thermal_bridge_width 0.5)
				(island_removal_mode 0)
			)
			(polygon
				(pts
					(arc
						(start 15.635732 -224.098358)
						(mid 12.384532 -224.098358)
						(end 15.635732 -224.098358)
					)
				)
			)
		)
	)
	(footprint ""
		(layer "B.Cu")
		(at 91.35364 -480.950524)
		(property "Reference" "U7"
			(at 4.463034 -0.439928 0)
			(unlocked yes)
			(layer "B.SilkS")
			(effects
				(font
					(size 0.7874 0.5842)
					(thickness 0.1524)
				)
				(justify left mirror)
			)
		)
		(property "Value" ""
			(at 0 0 0)
			(layer "B.Fab")
			(effects
				(font
					(size 1.27 1.27)
				)
				(justify mirror)
			)
		)
		(duplicate_pad_numbers_are_jumpers no)
		(fp_line
			(start -2.5527 -2.0066)
			(end -2.5527 2.0066)
			(stroke
				(width 0.1524)
				(type default)
			)
			(layer "B.SilkS")
		)
		(fp_line
			(start -2.5527 2.0066)
			(end 2.5527 2.0066)
			(stroke
				(width 0.1524)
				(type default)
			)
			(layer "B.SilkS")
		)
		(fp_line
			(start 1.9812 0)
			(end 2.5527 -0.5715)
			(stroke
				(width 0.1524)
				(type default)
			)
			(layer "B.SilkS")
		)
		(fp_line
			(start 2.5527 -2.0066)
			(end -2.5527 -2.0066)
			(stroke
				(width 0.1524)
				(type default)
			)
			(layer "B.SilkS")
		)
		(fp_line
			(start 2.5527 -0.5715)
			(end 2.5527 -2.0066)
			(stroke
				(width 0.1524)
				(type default)
			)
			(layer "B.SilkS")
		)
		(fp_line
			(start 2.5527 0.5715)
			(end 1.9812 0)
			(stroke
				(width 0.1524)
				(type default)
			)
			(layer "B.SilkS")
		)
		(fp_line
			(start 2.5527 2.0066)
			(end 2.5527 0.5715)
			(stroke
				(width 0.1524)
				(type default)
			)
			(layer "B.SilkS")
		)
		(fp_circle
			(center 2.032 1.524)
			(end 2.286 1.524)
			(stroke
				(width 0.1524)
				(type default)
			)
			(fill no)
			(layer "B.SilkS")
		)
		(fp_rect
			(start 2.5527 3.6703)
			(end -2.5527 -3.6703)
			(stroke
				(width 0)
				(type default)
			)
			(fill no)
			(layer "B.CrtYd")
		)
		(fp_line
			(start -2.549906 -2.249932)
			(end -2.549906 2.249932)
			(stroke
				(width 0.1)
				(type default)
			)
			(layer "B.Fab")
		)
		(fp_line
			(start -2.549906 2.249932)
			(end 2.549906 2.249932)
			(stroke
				(width 0.1)
				(type default)
			)
			(layer "B.Fab")
		)
		(fp_line
			(start 2.549906 -2.249932)
			(end -2.549906 -2.249932)
			(stroke
				(width 0.1)
				(type default)
			)
			(layer "B.Fab")
		)
		(fp_line
			(start 2.549906 2.249932)
			(end 2.549906 -2.249932)
			(stroke
				(width 0.1)
				(type default)
			)
			(layer "B.Fab")
		)
		(pad "1" smd rect
			(at 1.949958 2.921 180)
			(size 0.3556 1.4986)
			(layers "B.Cu" "B.Mask" "B.Paste")
			(net "PSU_ALERT_N")
		)
		(pad "2" smd rect
			(at 1.299972 2.921 180)
			(size 0.3556 1.4986)
			(layers "B.Cu" "B.Mask" "B.Paste")
			(net "B19_PSU_ALERT_N")
		)
		(pad "3" smd rect
			(at 0.649986 2.921 180)
			(size 0.3556 1.4986)
			(layers "B.Cu" "B.Mask" "B.Paste")
			(net "PSU_ALERT_N")
		)
		(pad "4" smd rect
			(at 0 2.921 180)
			(size 0.3556 1.4986)
			(layers "B.Cu" "B.Mask" "B.Paste")
			(net "B20_PSU_ALERT_N")
		)
		(pad "5" smd rect
			(at -0.649986 2.921 180)
			(size 0.3556 1.4986)
			(layers "B.Cu" "B.Mask" "B.Paste")
			(net "PSU_ALERT_N")
		)
		(pad "6" smd rect
			(at -1.299972 2.921 180)
			(size 0.3556 1.4986)
			(layers "B.Cu" "B.Mask" "B.Paste")
			(net "B21_PSU_ALERT_N")
		)
		(pad "7" smd rect
			(at -1.949958 2.921 180)
			(size 0.3556 1.4986)
			(layers "B.Cu" "B.Mask" "B.Paste")
			(net "GND")
		)
		(pad "8" smd rect
			(at -1.949958 -2.921 180)
			(size 0.3556 1.4986)
			(layers "B.Cu" "B.Mask" "B.Paste")
			(net "B22_PSU_ALERT_N")
		)
		(pad "9" smd rect
			(at -1.299972 -2.921 180)
			(size 0.3556 1.4986)
			(layers "B.Cu" "B.Mask" "B.Paste")
			(net "PSU_ALERT_N")
		)
		(pad "10" smd rect
			(at -0.649986 -2.921 180)
			(size 0.3556 1.4986)
			(layers "B.Cu" "B.Mask" "B.Paste")
			(net "B23_PSU_ALERT_N")
		)
		(pad "11" smd rect
			(at 0 -2.921 180)
			(size 0.3556 1.4986)
			(layers "B.Cu" "B.Mask" "B.Paste")
			(net "PSU_ALERT_N")
		)
		(pad "12" smd rect
			(at 0.649986 -2.921 180)
			(size 0.3556 1.4986)
			(layers "B.Cu" "B.Mask" "B.Paste")
			(net "B24_PSU_ALERT_N")
		)
		(pad "13" smd rect
			(at 1.299972 -2.921 180)
			(size 0.3556 1.4986)
			(layers "B.Cu" "B.Mask" "B.Paste")
			(net "PSU_ALERT_N")
		)
		(pad "14" smd rect
			(at 1.949958 -2.921 180)
			(size 0.3556 1.4986)
			(layers "B.Cu" "B.Mask" "B.Paste")
			(net "P3V3_BUF")
		)
	)
	(footprint ""
		(layer "B.Cu")
		(at 95.86595 -170.91787)
		(property "Reference" "C94"
			(at 1.284478 -1.115568 0)
			(unlocked yes)
			(layer "B.SilkS")
			(effects
				(font
					(size 0.7874 0.5842)
					(thickness 0.1524)
				)
				(justify left mirror)
			)
		)
		(property "Value" ""
			(at 0 0 0)
			(layer "B.Fab")
			(effects
				(font
					(size 1.27 1.27)
				)
				(justify mirror)
			)
		)
		(duplicate_pad_numbers_are_jumpers no)
		(fp_line
			(start -0.7874 -0.4064)
			(end -0.7874 0.4064)
			(stroke
				(width 0.1524)
				(type default)
			)
			(layer "B.SilkS")
		)
		(fp_line
			(start -0.7874 0.4064)
			(end 0.7874 0.4064)
			(stroke
				(width 0.1524)
				(type default)
			)
			(layer "B.SilkS")
		)
		(fp_line
			(start 0 0.381)
			(end 0 -0.381)
			(stroke
				(width 0.1524)
				(type default)
			)
			(layer "B.SilkS")
		)
		(fp_line
			(start 0.7874 -0.4064)
			(end -0.7874 -0.4064)
			(stroke
				(width 0.1524)
				(type default)
			)
			(layer "B.SilkS")
		)
		(fp_line
			(start 0.7874 0.4064)
			(end 0.7874 -0.4064)
			(stroke
				(width 0.1524)
				(type default)
			)
			(layer "B.SilkS")
		)
		(fp_poly
			(pts
				(xy 0.5334 0.254) (xy 0.635 0.254) (xy 0.635 0.2286) (xy 0.635 -0.254) (xy 0.5334 -0.254) (xy 0.5334 -0.2794)
				(xy -0.5334 -0.2794) (xy -0.5334 -0.254) (xy -0.635 -0.254) (xy -0.635 0.254) (xy -0.5334 0.254)
				(xy -0.5334 0.2794) (xy 0.508 0.2794) (xy 0.5334 0.2794)
			)
			(stroke
				(width 0)
				(type default)
			)
			(fill no)
			(layer "B.CrtYd")
		)
		(pad "1" smd rect
			(at -0.40005 0 180)
			(size 0.4572 0.508)
			(layers "B.Cu" "B.Mask" "B.Paste")
			(net "P3V3_BUF")
		)
		(pad "2" smd rect
			(at 0.40005 0 180)
			(size 0.4572 0.508)
			(layers "B.Cu" "B.Mask" "B.Paste")
			(net "GND")
		)
	)
)
